#ISCELL
  mstr_misc dns *
  *
#ISCELL
  pure_quanta quanta_title_block_c *
  *
#ISCELL
  pure_quanta_power vcc_core *
  page57_i27
#ISCELL
  pure_quanta_power vcc_core *
  page57_i28
#CELL
  pure_quanta genoa_sp5 *
  page57_i29
#ISCELL
  pure_quanta_power vcc_core *
  page57_i30
#ISCELL
  pure_quanta_power vcc_core *
  page57_i31
#CELL
  pure_quanta genoa_sp5 *
  page57_i32
#ISCELL
  pure_quanta_power vcc_core *
  page57_i36
#ISCELL
  pure_quanta_power universal_power *
  page57_i37
#ISCELL
  pure_quanta_power universal_power *
  page57_i38
#ISCELL
  pure_quanta_power vcc_core *
  page57_i41
#ISCELL
  pure_quanta_power universal_power *
  page57_i42
#ISCELL
  pure_quanta_power universal_power *
  page57_i44
#CELL
  pure_quanta genoa_sp5 *
  page57_i45
#CELL
  pure_quanta genoa_sp5 *
  page57_i46
#ISCELL
  pure_quanta_power vcc_core *
  page57_i47
#ISCELL
  pure_quanta_power vcc_core *
  page57_i48
#CELL
  pure_quanta genoa_sp5 *
  page57_i49
#CELL
  pure_quanta q_res *
  page57_i51
#CELL
  pure_quanta q_res *
  page57_i52
